# T6G (Grand Teton) — schematic netlist excerpt (pin names and nets, part order shuffled) for the footprints in the layout excerpt that follows; sources: Cadence DE-HDL packaged netlist, KiCad conversion of 04192023_DAF0TMB3IC0_F0TG_MB_C_brd_V02_OCP.brd

PR188  Q_RES  8.87K 1% EMPTY  pkg 0402LF  page 211 : A = GND ; B = PVDDCR_CPU0_P1_LSET2
PC6585  Q_CAP  560PF 50V 10% EMPTY  pkg C0402  page 363 : A = SW_P0V9_RETIMER_CPU0_SW2 ; B = SW_P0V9_RETIMER_CPU0_SW2_RC

(kicad_pcb
	(version 20260206)
	(generator "pcbnew")
	(generator_version "10.0")
	(general
		(thickness 1.6)
		(legacy_teardrops no)
	)
	(paper "A4")
	(title_block
		(title "04192023_DAF0TMB3IC0_F0TG_MB_C_brd_V02_OCP.brd")
		(comment 1 "Grand Teton / footprints 1933-1934 of 8354")
	)
	(layers
		(0 "F.Cu" signal "TOP")
		(4 "In1.Cu" signal "GND")
		(6 "In2.Cu" signal "IN1")
		(8 "In3.Cu" signal "GND1")
		(10 "In4.Cu" signal "IN2")
		(12 "In5.Cu" signal "GND2")
		(14 "In6.Cu" signal "IN3")
		(16 "In7.Cu" signal "GND3")
		(18 "In8.Cu" signal "VCC")
		(20 "In9.Cu" signal "VCC1")
		(22 "In10.Cu" signal "GND4")
		(24 "In11.Cu" signal "IN4")
		(26 "In12.Cu" signal "GND5")
		(28 "In13.Cu" signal "IN5")
		(30 "In14.Cu" signal "GND6")
		(32 "In15.Cu" signal "IN6")
		(34 "In16.Cu" signal "GND7")
		(2 "B.Cu" signal "BOTTOM")
		(9 "F.Adhes" user "F.Adhesive")
		(11 "B.Adhes" user "B.Adhesive")
		(13 "F.Paste" user "Package Geometry/Pastemask Top")
		(15 "B.Paste" user "Package Geometry/Pastemask Bottom")
		(5 "F.SilkS" user "Ref Des/Silkscreen Top")
		(7 "B.SilkS" user "Ref Des/Silkscreen Bottom")
		(1 "F.Mask" user "Board Geometry/Soldermask Top")
		(3 "B.Mask" user "Board Geometry/Soldermask Bottom")
		(17 "Dwgs.User" user "User.Drawings")
		(19 "Cmts.User" user "User.Comments")
		(21 "Eco1.User" user "User.Eco1")
		(23 "Eco2.User" user "User.Eco2")
		(25 "Edge.Cuts" user "Board Geometry/Outline")
		(27 "Margin" user)
		(31 "F.CrtYd" user "Package Geometry/Place Bound Top")
		(29 "B.CrtYd" user "Package Geometry/Place Bound Bottom")
		(35 "F.Fab" user "Ref Des/Assembly Top")
		(33 "B.Fab" user "Ref Des/Assembly Bottom")
	)
	(footprint ""
		(layer "F.Cu")
		(at 450.389752 -394.302234 180)
		(property "Reference" "PC6585"
			(at 0 0 180)
			(layer "F.SilkS")
			(hide yes)
			(effects
				(font
					(size 1.27 1.27)
				)
			)
		)
		(property "Value" ""
			(at 0 0 180)
			(layer "F.Fab")
			(effects
				(font
					(size 1.27 1.27)
				)
			)
		)
		(duplicate_pad_numbers_are_jumpers no)
		(fp_line
			(start 0.7874 0.4064)
			(end -0.7874 0.4064)
			(stroke
				(width 0.1524)
				(type default)
			)
			(layer "F.SilkS")
		)
		(fp_line
			(start 0.7874 -0.4064)
			(end 0.7874 0.4064)
			(stroke
				(width 0.1524)
				(type default)
			)
			(layer "F.SilkS")
		)
		(fp_line
			(start -0.7874 0.4064)
			(end -0.7874 -0.4064)
			(stroke
				(width 0.1524)
				(type default)
			)
			(layer "F.SilkS")
		)
		(fp_line
			(start -0.7874 -0.4064)
			(end 0.7874 -0.4064)
			(stroke
				(width 0.1524)
				(type default)
			)
			(layer "F.SilkS")
		)
		(fp_line
			(start 0.67945 0.3048)
			(end 0.120396 0.3048)
			(stroke
				(width 0.1)
				(type default)
			)
			(layer "F.Fab")
		)
		(fp_line
			(start 0.67945 -0.3048)
			(end 0.67945 0.3048)
			(stroke
				(width 0.1)
				(type default)
			)
			(layer "F.Fab")
		)
		(fp_line
			(start 0.12065 -0.2794)
			(end 0.12065 -0.3048)
			(stroke
				(width 0.1)
				(type default)
			)
			(layer "F.Fab")
		)
		(fp_line
			(start 0.12065 -0.3048)
			(end 0.67945 -0.3048)
			(stroke
				(width 0.1)
				(type default)
			)
			(layer "F.Fab")
		)
		(fp_line
			(start 0.120396 0.3048)
			(end 0.120396 0.2794)
			(stroke
				(width 0.1)
				(type default)
			)
			(layer "F.Fab")
		)
		(fp_line
			(start 0.120396 0.2794)
			(end -0.12065 0.2794)
			(stroke
				(width 0.1)
				(type default)
			)
			(layer "F.Fab")
		)
		(fp_line
			(start -0.12065 0.3048)
			(end -0.67945 0.3048)
			(stroke
				(width 0.1)
				(type default)
			)
			(layer "F.Fab")
		)
		(fp_line
			(start -0.12065 0.2794)
			(end -0.12065 0.3048)
			(stroke
				(width 0.1)
				(type default)
			)
			(layer "F.Fab")
		)
		(fp_line
			(start -0.12065 -0.2794)
			(end 0.12065 -0.2794)
			(stroke
				(width 0.1)
				(type default)
			)
			(layer "F.Fab")
		)
		(fp_line
			(start -0.12065 -0.305054)
			(end -0.12065 -0.2794)
			(stroke
				(width 0.1)
				(type default)
			)
			(layer "F.Fab")
		)
		(fp_line
			(start -0.67945 0.3048)
			(end -0.67945 -0.305054)
			(stroke
				(width 0.1)
				(type default)
			)
			(layer "F.Fab")
		)
		(fp_line
			(start -0.67945 -0.305054)
			(end -0.12065 -0.305054)
			(stroke
				(width 0.1)
				(type default)
			)
			(layer "F.Fab")
		)
		(pad "1" smd circle
			(at -0.40005 0 180)
			(size 0 0)
			(layers "F.Cu" "F.Mask" "F.Paste")
			(net "SW_P0V9_RETIMER_CPU0_SW2")
		)
		(pad "2" smd circle
			(at 0.40005 0 180)
			(size 0 0)
			(layers "F.Cu" "F.Mask" "F.Paste")
			(net "SW_P0V9_RETIMER_CPU0_SW2_RC")
		)
	)
	(footprint ""
		(layer "F.Cu")
		(at 91.986354 -177.464212)
		(property "Reference" "PR188"
			(at 0 0 0)
			(layer "F.SilkS")
			(hide yes)
			(effects
				(font
					(size 1.27 1.27)
				)
			)
		)
		(property "Value" ""
			(at 0 0 0)
			(layer "F.Fab")
			(effects
				(font
					(size 1.27 1.27)
				)
			)
		)
		(duplicate_pad_numbers_are_jumpers no)
		(fp_line
			(start -0.7874 -0.4064)
			(end 0.7874 -0.4064)
			(stroke
				(width 0.1524)
				(type default)
			)
			(layer "F.SilkS")
		)
		(fp_line
			(start -0.7874 0.4064)
			(end -0.7874 -0.4064)
			(stroke
				(width 0.1524)
				(type default)
			)
			(layer "F.SilkS")
		)
		(fp_line
			(start 0.7874 -0.4064)
			(end 0.7874 0.4064)
			(stroke
				(width 0.1524)
				(type default)
			)
			(layer "F.SilkS")
		)
		(fp_line
			(start 0.7874 0.4064)
			(end -0.7874 0.4064)
			(stroke
				(width 0.1524)
				(type default)
			)
			(layer "F.SilkS")
		)
		(fp_line
			(start -0.67945 -0.305054)
			(end -0.12065 -0.305054)
			(stroke
				(width 0.1)
				(type default)
			)
			(layer "F.Fab")
		)
		(fp_line
			(start -0.67945 0.3048)
			(end -0.67945 -0.305054)
			(stroke
				(width 0.1)
				(type default)
			)
			(layer "F.Fab")
		)
		(fp_line
			(start -0.12065 -0.305054)
			(end -0.12065 -0.2794)
			(stroke
				(width 0.1)
				(type default)
			)
			(layer "F.Fab")
		)
		(fp_line
			(start -0.12065 -0.2794)
			(end 0.12065 -0.2794)
			(stroke
				(width 0.1)
				(type default)
			)
			(layer "F.Fab")
		)
		(fp_line
			(start -0.12065 0.2794)
			(end -0.12065 0.3048)
			(stroke
				(width 0.1)
				(type default)
			)
			(layer "F.Fab")
		)
		(fp_line
			(start -0.12065 0.3048)
			(end -0.67945 0.3048)
			(stroke
				(width 0.1)
				(type default)
			)
			(layer "F.Fab")
		)
		(fp_line
			(start 0.120396 0.2794)
			(end -0.12065 0.2794)
			(stroke
				(width 0.1)
				(type default)
			)
			(layer "F.Fab")
		)
		(fp_line
			(start 0.120396 0.3048)
			(end 0.120396 0.2794)
			(stroke
				(width 0.1)
				(type default)
			)
			(layer "F.Fab")
		)
		(fp_line
			(start 0.12065 -0.3048)
			(end 0.67945 -0.3048)
			(stroke
				(width 0.1)
				(type default)
			)
			(layer "F.Fab")
		)
		(fp_line
			(start 0.12065 -0.2794)
			(end 0.12065 -0.3048)
			(stroke
				(width 0.1)
				(type default)
			)
			(layer "F.Fab")
		)
		(fp_line
			(start 0.67945 -0.3048)
			(end 0.67945 0.3048)
			(stroke
				(width 0.1)
				(type default)
			)
			(layer "F.Fab")
		)
		(fp_line
			(start 0.67945 0.3048)
			(end 0.120396 0.3048)
			(stroke
				(width 0.1)
				(type default)
			)
			(layer "F.Fab")
		)
		(pad "1" smd circle
			(at -0.40005 0)
			(size 0 0)
			(layers "F.Cu" "F.Mask" "F.Paste")
			(net "GND")
		)
		(pad "2" smd circle
			(at 0.40005 0)
			(size 0 0)
			(layers "F.Cu" "F.Mask" "F.Paste")
			(net "PVDDCR_CPU0_P1_LSET2")
		)
	)
)
